(kicad_pcb
	(version 20241229)
	(generator "pcbnew")
	(generator_version "9.0")
	(general
		(thickness 1.61)
		(legacy_teardrops no)
	)
	(paper "A3")
	(title_block
		(title "SO-DIMM DDR5 Tester")
		(date "2025-11-26")
		(rev "1.3.0")
		(comment 9 "footprints 363-369 of 627")
	)
	(layers
		(0 "F.Cu" signal)
		(4 "In1.Cu" power)
		(6 "In2.Cu" mixed)
		(8 "In3.Cu" power)
		(10 "In4.Cu" mixed)
		(12 "In5.Cu" power)
		(14 "In6.Cu" mixed)
		(16 "In7.Cu" power)
		(18 "In8.Cu" power)
		(20 "In9.Cu" mixed)
		(22 "In10.Cu" power)
		(2 "B.Cu" signal)
		(9 "F.Adhes" user "F.Adhesive")
		(11 "B.Adhes" user "B.Adhesive")
		(13 "F.Paste" user)
		(15 "B.Paste" user)
		(5 "F.SilkS" user "F.Silkscreen")
		(7 "B.SilkS" user "B.Silkscreen")
		(1 "F.Mask" user)
		(3 "B.Mask" user)
		(17 "Dwgs.User" user "User.Drawings")
		(19 "Cmts.User" user "User.Comments")
		(21 "Eco1.User" user "User.Eco1")
		(23 "Eco2.User" user "User.Eco2")
		(25 "Edge.Cuts" user)
		(27 "Margin" user)
		(31 "F.CrtYd" user "F.Courtyard")
		(29 "B.CrtYd" user "B.Courtyard")
		(35 "F.Fab" user)
		(33 "B.Fab" user)
	)
	(footprint "antmicro-footprints:R_0402_1005Metric"
		(layer "B.Cu")
		(at 94.258672 154.95 90)
		(descr "Resistor SMD 0402")
		(tags "resistor SMD 0402")
		(property "Reference" "R119"
			(at -1.122484 0.772697 270)
			(layer "B.SilkS")
			(hide yes)
			(effects
				(font
					(size 0.7 0.7)
					(thickness 0.15)
				)
				(justify left bottom mirror)
			)
		)
		(property "Value" "R_2k2_0402"
			(at -1.011843 -1.772047 270)
			(layer "B.Fab")
			(effects
				(font
					(size 0.7 0.7)
					(thickness 0.15)
				)
				(justify left bottom mirror)
			)
		)
		(property "Datasheet" "https://www.bourns.com/docs/product-datasheets/cr.pdf"
			(at 0 0 90)
			(layer "F.Fab")
			(hide yes)
			(effects
				(font
					(size 1.27 1.27)
					(thickness 0.15)
				)
			)
		)
		(property "Author" "Antmicro"
			(at 249.208672 60.691328 0)
			(layer "B.Fab")
			(hide yes)
			(effects
				(font
					(size 1 1)
					(thickness 0.15)
				)
				(justify mirror)
			)
		)
		(property "License" "Apache-2.0"
			(at 249.208672 60.691328 0)
			(layer "B.Fab")
			(hide yes)
			(effects
				(font
					(size 1 1)
					(thickness 0.15)
				)
				(justify mirror)
			)
		)
		(property "MPN" "CR0402-FX-2201GLF"
			(at 249.208672 60.691328 0)
			(layer "B.Fab")
			(hide yes)
			(effects
				(font
					(size 1 1)
					(thickness 0.15)
				)
				(justify mirror)
			)
		)
		(property "Manufacturer" "Bourns"
			(at 249.208672 60.691328 0)
			(layer "B.Fab")
			(hide yes)
			(effects
				(font
					(size 1 1)
					(thickness 0.15)
				)
				(justify mirror)
			)
		)
		(property "Tolerance" "1%"
			(at 249.208672 60.691328 0)
			(layer "B.Fab")
			(hide yes)
			(effects
				(font
					(size 1 1)
					(thickness 0.15)
				)
				(justify mirror)
			)
		)
		(property "Val" "2k2"
			(at 249.208672 60.691328 0)
			(layer "B.Fab")
			(hide yes)
			(effects
				(font
					(size 1 1)
					(thickness 0.15)
				)
				(justify mirror)
			)
		)
		(sheetname "/Ethernet/")
		(sheetfile "ethernet.kicad_sch")
		(attr exclude_from_pos_files exclude_from_bom dnp)
		(fp_rect
			(start -0.93 0.47)
			(end 0.93 -0.47)
			(stroke
				(width 0.05)
				(type solid)
			)
			(fill no)
			(layer "B.CrtYd")
		)
		(fp_rect
			(start -0.5 0.25)
			(end 0.5 -0.25)
			(stroke
				(width 0.15)
				(type solid)
			)
			(fill no)
			(layer "B.Fab")
		)
		(pad "1" smd roundrect
			(at -0.485 0 90)
			(size 0.59 0.64)
			(layers "B.Cu" "B.Mask" "B.Paste")
			(roundrect_rratio 0.25)
			(net 679 "/Ethernet/ETH.REF_CLK")
			(pintype "passive")
		)
		(pad "2" smd roundrect
			(at 0.485 0 90)
			(size 0.59 0.64)
			(layers "B.Cu" "B.Mask" "B.Paste")
			(roundrect_rratio 0.25)
			(net 1 "GND")
			(pintype "passive")
		)
	)
	(footprint "antmicro-footprints:R_0402_1005Metric"
		(layer "B.Cu")
		(at 85.680501 151.353149 90)
		(descr "Resistor SMD 0402")
		(tags "resistor SMD 0402")
		(property "Reference" "R120"
			(at -1.122484 0.772697 270)
			(layer "B.SilkS")
			(hide yes)
			(effects
				(font
					(size 0.7 0.7)
					(thickness 0.15)
				)
				(justify left bottom mirror)
			)
		)
		(property "Value" "R_2k2_0402"
			(at -1.011843 -1.772047 270)
			(layer "B.Fab")
			(effects
				(font
					(size 0.7 0.7)
					(thickness 0.15)
				)
				(justify left bottom mirror)
			)
		)
		(property "Datasheet" "https://www.bourns.com/docs/product-datasheets/cr.pdf"
			(at 0 0 90)
			(layer "F.Fab")
			(hide yes)
			(effects
				(font
					(size 1.27 1.27)
					(thickness 0.15)
				)
			)
		)
		(property "Author" "Antmicro"
			(at 237.03365 65.672648 0)
			(layer "B.Fab")
			(hide yes)
			(effects
				(font
					(size 1 1)
					(thickness 0.15)
				)
				(justify mirror)
			)
		)
		(property "License" "Apache-2.0"
			(at 237.03365 65.672648 0)
			(layer "B.Fab")
			(hide yes)
			(effects
				(font
					(size 1 1)
					(thickness 0.15)
				)
				(justify mirror)
			)
		)
		(property "MPN" "CR0402-FX-2201GLF"
			(at 237.03365 65.672648 0)
			(layer "B.Fab")
			(hide yes)
			(effects
				(font
					(size 1 1)
					(thickness 0.15)
				)
				(justify mirror)
			)
		)
		(property "Manufacturer" "Bourns"
			(at 237.03365 65.672648 0)
			(layer "B.Fab")
			(hide yes)
			(effects
				(font
					(size 1 1)
					(thickness 0.15)
				)
				(justify mirror)
			)
		)
		(property "Tolerance" "1%"
			(at 237.03365 65.672648 0)
			(layer "B.Fab")
			(hide yes)
			(effects
				(font
					(size 1 1)
					(thickness 0.15)
				)
				(justify mirror)
			)
		)
		(property "Val" "2k2"
			(at 237.03365 65.672648 0)
			(layer "B.Fab")
			(hide yes)
			(effects
				(font
					(size 1 1)
					(thickness 0.15)
				)
				(justify mirror)
			)
		)
		(sheetname "/Ethernet/")
		(sheetfile "ethernet.kicad_sch")
		(attr exclude_from_pos_files exclude_from_bom dnp)
		(fp_rect
			(start -0.93 0.47)
			(end 0.93 -0.47)
			(stroke
				(width 0.05)
				(type solid)
			)
			(fill no)
			(layer "B.CrtYd")
		)
		(fp_rect
			(start -0.5 0.25)
			(end 0.5 -0.25)
			(stroke
				(width 0.15)
				(type solid)
			)
			(fill no)
			(layer "B.Fab")
		)
		(pad "1" smd roundrect
			(at -0.485 0 90)
			(size 0.59 0.64)
			(layers "B.Cu" "B.Mask" "B.Paste")
			(roundrect_rratio 0.25)
			(net 602 "/Ethernet/LED_SPD")
			(pintype "passive")
		)
		(pad "2" smd roundrect
			(at 0.485 0 90)
			(size 0.59 0.64)
			(layers "B.Cu" "B.Mask" "B.Paste")
			(roundrect_rratio 0.25)
			(net 1 "GND")
			(pintype "passive")
		)
	)
	(footprint "antmicro-footprints:R_0402_1005Metric"
		(layer "B.Cu")
		(at 85.680501 155.763149 -90)
		(descr "Resistor SMD 0402")
		(tags "resistor SMD 0402")
		(property "Reference" "R121"
			(at -1.122484 0.772697 90)
			(layer "B.SilkS")
			(hide yes)
			(effects
				(font
					(size 0.7 0.7)
					(thickness 0.15)
				)
				(justify left bottom mirror)
			)
		)
		(property "Value" "R_2k2_0402"
			(at -1.011843 -1.772047 90)
			(layer "B.Fab")
			(effects
				(font
					(size 0.7 0.7)
					(thickness 0.15)
				)
				(justify left bottom mirror)
			)
		)
		(property "Datasheet" "https://www.bourns.com/docs/product-datasheets/cr.pdf"
			(at 0 0 270)
			(layer "F.Fab")
			(hide yes)
			(effects
				(font
					(size 1.27 1.27)
					(thickness 0.15)
				)
			)
		)
		(property "Author" "Antmicro"
			(at -70.082648 241.44365 0)
			(layer "B.Fab")
			(hide yes)
			(effects
				(font
					(size 1 1)
					(thickness 0.15)
				)
				(justify mirror)
			)
		)
		(property "License" "Apache-2.0"
			(at -70.082648 241.44365 0)
			(layer "B.Fab")
			(hide yes)
			(effects
				(font
					(size 1 1)
					(thickness 0.15)
				)
				(justify mirror)
			)
		)
		(property "MPN" "CR0402-FX-2201GLF"
			(at -70.082648 241.44365 0)
			(layer "B.Fab")
			(hide yes)
			(effects
				(font
					(size 1 1)
					(thickness 0.15)
				)
				(justify mirror)
			)
		)
		(property "Manufacturer" "Bourns"
			(at -70.082648 241.44365 0)
			(layer "B.Fab")
			(hide yes)
			(effects
				(font
					(size 1 1)
					(thickness 0.15)
				)
				(justify mirror)
			)
		)
		(property "Tolerance" "1%"
			(at -70.082648 241.44365 0)
			(layer "B.Fab")
			(hide yes)
			(effects
				(font
					(size 1 1)
					(thickness 0.15)
				)
				(justify mirror)
			)
		)
		(property "Val" "2k2"
			(at -70.082648 241.44365 0)
			(layer "B.Fab")
			(hide yes)
			(effects
				(font
					(size 1 1)
					(thickness 0.15)
				)
				(justify mirror)
			)
		)
		(sheetname "/Ethernet/")
		(sheetfile "ethernet.kicad_sch")
		(attr exclude_from_pos_files exclude_from_bom dnp)
		(fp_rect
			(start -0.93 0.47)
			(end 0.93 -0.47)
			(stroke
				(width 0.05)
				(type solid)
			)
			(fill no)
			(layer "B.CrtYd")
		)
		(fp_rect
			(start -0.5 0.25)
			(end 0.5 -0.25)
			(stroke
				(width 0.15)
				(type solid)
			)
			(fill no)
			(layer "B.Fab")
		)
		(pad "1" smd roundrect
			(at -0.485 0 270)
			(size 0.59 0.64)
			(layers "B.Cu" "B.Mask" "B.Paste")
			(roundrect_rratio 0.25)
			(net 603 "/Ethernet/LED_LINK")
			(pintype "passive")
		)
		(pad "2" smd roundrect
			(at 0.485 0 270)
			(size 0.59 0.64)
			(layers "B.Cu" "B.Mask" "B.Paste")
			(roundrect_rratio 0.25)
			(net 1 "GND")
			(pintype "passive")
		)
	)
	(footprint "antmicro-footprints:R_0402_1005Metric"
		(layer "B.Cu")
		(at 96.375501 161.576 90)
		(descr "Resistor SMD 0402")
		(tags "resistor SMD 0402")
		(property "Reference" "R104"
			(at -1.122484 0.772697 270)
			(layer "B.SilkS")
			(hide yes)
			(effects
				(font
					(size 0.7 0.7)
					(thickness 0.15)
				)
				(justify left bottom mirror)
			)
		)
		(property "Value" "R_10k_0402"
			(at -1.011843 -1.772047 270)
			(layer "B.Fab")
			(effects
				(font
					(size 0.7 0.7)
					(thickness 0.15)
				)
				(justify left bottom mirror)
			)
		)
		(property "Datasheet" "https://www.bourns.com/docs/product-datasheets/cr.pdf"
			(at 0 0 90)
			(layer "F.Fab")
			(hide yes)
			(effects
				(font
					(size 1.27 1.27)
					(thickness 0.15)
				)
			)
		)
		(property "Author" "Antmicro"
			(at 257.951501 65.200499 0)
			(layer "B.Fab")
			(hide yes)
			(effects
				(font
					(size 1 1)
					(thickness 0.15)
				)
				(justify mirror)
			)
		)
		(property "License" "Apache-2.0"
			(at 257.951501 65.200499 0)
			(layer "B.Fab")
			(hide yes)
			(effects
				(font
					(size 1 1)
					(thickness 0.15)
				)
				(justify mirror)
			)
		)
		(property "MPN" "CR0402-FX-1002GLF"
			(at 257.951501 65.200499 0)
			(layer "B.Fab")
			(hide yes)
			(effects
				(font
					(size 1 1)
					(thickness 0.15)
				)
				(justify mirror)
			)
		)
		(property "Manufacturer" "Bourns"
			(at 257.951501 65.200499 0)
			(layer "B.Fab")
			(hide yes)
			(effects
				(font
					(size 1 1)
					(thickness 0.15)
				)
				(justify mirror)
			)
		)
		(property "Tolerance" "1%"
			(at 257.951501 65.200499 0)
			(layer "B.Fab")
			(hide yes)
			(effects
				(font
					(size 1 1)
					(thickness 0.15)
				)
				(justify mirror)
			)
		)
		(property "Val" "10k"
			(at 257.951501 65.200499 0)
			(layer "B.Fab")
			(hide yes)
			(effects
				(font
					(size 1 1)
					(thickness 0.15)
				)
				(justify mirror)
			)
		)
		(sheetname "/Ethernet/")
		(sheetfile "ethernet.kicad_sch")
		(attr smd)
		(fp_rect
			(start -0.93 0.47)
			(end 0.93 -0.47)
			(stroke
				(width 0.05)
				(type solid)
			)
			(fill no)
			(layer "B.CrtYd")
		)
		(fp_rect
			(start -0.5 0.25)
			(end 0.5 -0.25)
			(stroke
				(width 0.15)
				(type solid)
			)
			(fill no)
			(layer "B.Fab")
		)
		(pad "1" smd roundrect
			(at -0.485 0 90)
			(size 0.59 0.64)
			(layers "B.Cu" "B.Mask" "B.Paste")
			(roundrect_rratio 0.25)
			(net 676 "/Ethernet/ETH.RXD3")
			(pintype "passive")
		)
		(pad "2" smd roundrect
			(at 0.485 0 90)
			(size 0.59 0.64)
			(layers "B.Cu" "B.Mask" "B.Paste")
			(roundrect_rratio 0.25)
			(net 200 "+3V3")
			(pintype "passive")
		)
	)
	(footprint "antmicro-footprints:R_0402_1005Metric"
		(layer "B.Cu")
		(at 96.375501 163.951 -90)
		(descr "Resistor SMD 0402")
		(tags "resistor SMD 0402")
		(property "Reference" "R116"
			(at -1.122484 0.772697 90)
			(layer "B.SilkS")
			(hide yes)
			(effects
				(font
					(size 0.7 0.7)
					(thickness 0.15)
				)
				(justify left bottom mirror)
			)
		)
		(property "Value" "R_2k2_0402"
			(at -1.011843 -1.772047 90)
			(layer "B.Fab")
			(effects
				(font
					(size 0.7 0.7)
					(thickness 0.15)
				)
				(justify left bottom mirror)
			)
		)
		(property "Datasheet" "https://www.bourns.com/docs/product-datasheets/cr.pdf"
			(at 0 0 270)
			(layer "F.Fab")
			(hide yes)
			(effects
				(font
					(size 1.27 1.27)
					(thickness 0.15)
				)
			)
		)
		(property "Author" "Antmicro"
			(at -67.575499 260.326501 0)
			(layer "B.Fab")
			(hide yes)
			(effects
				(font
					(size 1 1)
					(thickness 0.15)
				)
				(justify mirror)
			)
		)
		(property "License" "Apache-2.0"
			(at -67.575499 260.326501 0)
			(layer "B.Fab")
			(hide yes)
			(effects
				(font
					(size 1 1)
					(thickness 0.15)
				)
				(justify mirror)
			)
		)
		(property "MPN" "CR0402-FX-2201GLF"
			(at -67.575499 260.326501 0)
			(layer "B.Fab")
			(hide yes)
			(effects
				(font
					(size 1 1)
					(thickness 0.15)
				)
				(justify mirror)
			)
		)
		(property "Manufacturer" "Bourns"
			(at -67.575499 260.326501 0)
			(layer "B.Fab")
			(hide yes)
			(effects
				(font
					(size 1 1)
					(thickness 0.15)
				)
				(justify mirror)
			)
		)
		(property "Tolerance" "1%"
			(at -67.575499 260.326501 0)
			(layer "B.Fab")
			(hide yes)
			(effects
				(font
					(size 1 1)
					(thickness 0.15)
				)
				(justify mirror)
			)
		)
		(property "Val" "2k2"
			(at -67.575499 260.326501 0)
			(layer "B.Fab")
			(hide yes)
			(effects
				(font
					(size 1 1)
					(thickness 0.15)
				)
				(justify mirror)
			)
		)
		(sheetname "/Ethernet/")
		(sheetfile "ethernet.kicad_sch")
		(attr exclude_from_pos_files exclude_from_bom dnp)
		(fp_rect
			(start -0.93 0.47)
			(end 0.93 -0.47)
			(stroke
				(width 0.05)
				(type solid)
			)
			(fill no)
			(layer "B.CrtYd")
		)
		(fp_rect
			(start -0.5 0.25)
			(end 0.5 -0.25)
			(stroke
				(width 0.15)
				(type solid)
			)
			(fill no)
			(layer "B.Fab")
		)
		(pad "1" smd roundrect
			(at -0.485 0 270)
			(size 0.59 0.64)
			(layers "B.Cu" "B.Mask" "B.Paste")
			(roundrect_rratio 0.25)
			(net 676 "/Ethernet/ETH.RXD3")
			(pintype "passive")
		)
		(pad "2" smd roundrect
			(at 0.485 0 270)
			(size 0.59 0.64)
			(layers "B.Cu" "B.Mask" "B.Paste")
			(roundrect_rratio 0.25)
			(net 1 "GND")
			(pintype "passive")
		)
	)
	(footprint "antmicro-footprints:TP_SMD_1mm"
		(layer "B.Cu")
		(at 96.8 178.05 -90)
		(property "Reference" "TP1"
			(at -0.95 0.8 90)
			(layer "B.SilkS")
			(effects
				(font
					(size 0.7 0.7)
					(thickness 0.15)
				)
				(justify left bottom mirror)
			)
		)
		(property "Value" "TP_1mm_SMD"
			(at 0 -1.4 90)
			(layer "B.Fab")
			(effects
				(font
					(size 0.7 0.7)
					(thickness 0.15)
				)
				(justify left bottom mirror)
			)
		)
		(property "Author" "Antmicro"
			(at -81.25 274.85 0)
			(layer "B.Fab")
			(hide yes)
			(effects
				(font
					(size 1 1)
					(thickness 0.15)
				)
				(justify mirror)
			)
		)
		(property "License" "Apache-2.0"
			(at -81.25 274.85 0)
			(layer "B.Fab")
			(hide yes)
			(effects
				(font
					(size 1 1)
					(thickness 0.15)
				)
				(justify mirror)
			)
		)
		(property "MPN" ""
			(at -81.25 274.85 0)
			(layer "B.Fab")
			(hide yes)
			(effects
				(font
					(size 1 1)
					(thickness 0.15)
				)
				(justify mirror)
			)
		)
		(property "Manufacturer" ""
			(at -81.25 274.85 0)
			(layer "B.Fab")
			(hide yes)
			(effects
				(font
					(size 1 1)
					(thickness 0.15)
				)
				(justify mirror)
			)
		)
		(sheetname "/Debug FTDI/")
		(sheetfile "debug-ftdi.kicad_sch")
		(attr exclude_from_pos_files)
		(pad "1" smd circle
			(at 0 0 270)
			(size 1 1)
			(layers "B.Cu" "B.Mask")
			(net 692 "/Debug FTDI/FTDI_JTAG_RST")
			(pinfunction "1")
			(pintype "passive")
		)
	)
	(footprint "antmicro-footprints:R_0402_1005Metric"
		(layer "B.Cu")
		(at 98.475501 163.951 -90)
		(descr "Resistor SMD 0402")
		(tags "resistor SMD 0402")
		(property "Reference" "R114"
			(at -1.122484 0.772697 90)
			(layer "B.SilkS")
			(hide yes)
			(effects
				(font
					(size 0.7 0.7)
					(thickness 0.15)
				)
				(justify left bottom mirror)
			)
		)
		(property "Value" "R_2k2_0402"
			(at -1.011843 -1.772047 90)
			(layer "B.Fab")
			(effects
				(font
					(size 0.7 0.7)
					(thickness 0.15)
				)
				(justify left bottom mirror)
			)
		)
		(property "Datasheet" "https://www.bourns.com/docs/product-datasheets/cr.pdf"
			(at 0 0 270)
			(layer "F.Fab")
			(hide yes)
			(effects
				(font
					(size 1.27 1.27)
					(thickness 0.15)
				)
			)
		)
		(property "Author" "Antmicro"
			(at -65.475499 262.426501 0)
			(layer "B.Fab")
			(hide yes)
			(effects
				(font
					(size 1 1)
					(thickness 0.15)
				)
				(justify mirror)
			)
		)
		(property "License" "Apache-2.0"
			(at -65.475499 262.426501 0)
			(layer "B.Fab")
			(hide yes)
			(effects
				(font
					(size 1 1)
					(thickness 0.15)
				)
				(justify mirror)
			)
		)
		(property "MPN" "CR0402-FX-2201GLF"
			(at -65.475499 262.426501 0)
			(layer "B.Fab")
			(hide yes)
			(effects
				(font
					(size 1 1)
					(thickness 0.15)
				)
				(justify mirror)
			)
		)
		(property "Manufacturer" "Bourns"
			(at -65.475499 262.426501 0)
			(layer "B.Fab")
			(hide yes)
			(effects
				(font
					(size 1 1)
					(thickness 0.15)
				)
				(justify mirror)
			)
		)
		(property "Tolerance" "1%"
			(at -65.475499 262.426501 0)
			(layer "B.Fab")
			(hide yes)
			(effects
				(font
					(size 1 1)
					(thickness 0.15)
				)
				(justify mirror)
			)
		)
		(property "Val" "2k2"
			(at -65.475499 262.426501 0)
			(layer "B.Fab")
			(hide yes)
			(effects
				(font
					(size 1 1)
					(thickness 0.15)
				)
				(justify mirror)
			)
		)
		(sheetname "/Ethernet/")
		(sheetfile "ethernet.kicad_sch")
		(attr smd)
		(fp_rect
			(start -0.93 0.47)
			(end 0.93 -0.47)
			(stroke
				(width 0.05)
				(type solid)
			)
			(fill no)
			(layer "B.CrtYd")
		)
		(fp_rect
			(start -0.5 0.25)
			(end 0.5 -0.25)
			(stroke
				(width 0.15)
				(type solid)
			)
			(fill no)
			(layer "B.Fab")
		)
		(pad "1" smd roundrect
			(at -0.485 0 270)
			(size 0.59 0.64)
			(layers "B.Cu" "B.Mask" "B.Paste")
			(roundrect_rratio 0.25)
			(net 674 "/Ethernet/ETH.RXD1")
			(pintype "passive")
		)
		(pad "2" smd roundrect
			(at 0.485 0 270)
			(size 0.59 0.64)
			(layers "B.Cu" "B.Mask" "B.Paste")
			(roundrect_rratio 0.25)
			(net 1 "GND")
			(pintype "passive")
		)
	)
)
